(kicad_pcb
	(version 20260206)
	(generator "pcbnew")
	(generator_version "10.0")
	(general
		(thickness 1.6)
		(legacy_teardrops no)
	)
	(paper "A4")
	(title_block
		(title "baseboard — 13948-1b.1110WZS1818.brd")
		(comment 1 "Honey Badger (Wiwynn) / footprints 2461-2469 of 2523")
	)
	(layers
		(0 "F.Cu" signal "TOP")
		(4 "In1.Cu" signal "L2GND")
		(6 "In2.Cu" signal "L3")
		(8 "In3.Cu" signal "L4VCC")
		(10 "In4.Cu" signal "L5VCC")
		(12 "In5.Cu" signal "L6")
		(14 "In6.Cu" signal "L7GND")
		(2 "B.Cu" signal "BOTTOM")
		(9 "F.Adhes" user "F.Adhesive")
		(11 "B.Adhes" user "B.Adhesive")
		(13 "F.Paste" user "Package Geometry/Pastemask Top")
		(15 "B.Paste" user "Package Geometry/Pastemask Bottom")
		(5 "F.SilkS" user "Ref Des/Silkscreen Top")
		(7 "B.SilkS" user "Ref Des/Silkscreen Bottom")
		(1 "F.Mask" user "Board Geometry/Soldermask Top")
		(3 "B.Mask" user "Board Geometry/Soldermask Bottom")
		(17 "Dwgs.User" user "User.Drawings")
		(19 "Cmts.User" user "User.Comments")
		(21 "Eco1.User" user "User.Eco1")
		(23 "Eco2.User" user "User.Eco2")
		(25 "Edge.Cuts" user "Board Geometry/Outline")
		(27 "Margin" user)
		(31 "F.CrtYd" user "Package Geometry/Place Bound Top")
		(29 "B.CrtYd" user "Package Geometry/Place Bound Bottom")
		(35 "F.Fab" user "Ref Des/Assembly Top")
		(33 "B.Fab" user "Ref Des/Assembly Bottom")
	)
	(footprint ""
		(layer "B.Cu")
		(at 103.87457 -94.488 -90)
		(property "Reference" "SC1214"
			(at 0 0 90)
			(layer "B.SilkS")
			(hide yes)
			(effects
				(font
					(size 1.27 1.27)
				)
				(justify mirror)
			)
		)
		(property "Value" "SC1KP50V2KX-1GP"
			(at -1.1811 -2.7051 270)
			(unlocked yes)
			(layer "B.Fab")
			(hide yes)
			(effects
				(font
					(size 1.016 1.016)
					(thickness 0.1524)
				)
				(justify mirror)
			)
		)
		(property "Device Type" "C402H22"
			(at -1.1811 -4.2291 270)
			(unlocked yes)
			(layer "B.Fab")
			(hide yes)
			(effects
				(font
					(size 1.016 1.016)
					(thickness 0.1524)
				)
				(justify mirror)
			)
		)
		(duplicate_pad_numbers_are_jumpers no)
		(fp_rect
			(start 0.4318 0.9525)
			(end -0.4318 -0.9525)
			(stroke
				(width 0)
				(type default)
			)
			(fill no)
			(layer "B.CrtYd")
		)
		(fp_rect
			(start 0.4318 0.9525)
			(end -0.4318 -0.9525)
			(stroke
				(width 0)
				(type default)
			)
			(fill no)
			(layer "B.Fab")
		)
		(pad "1" smd custom
			(at 0 -0.4445 90)
			(size 0.1524 0.1524)
			(layers "B.Cu" "B.Mask" "B.Paste")
			(net "P1V8_E")
			(options
				(clearance outline)
				(anchor circle)
			)
			(primitives
				(gr_poly
					(pts
						(arc
							(start 0.3048 0.2032)
							(mid 0.275042 0.275042)
							(end 0.2032 0.3048)
						)
						(arc
							(start -0.2032 0.3048)
							(mid -0.275042 0.275042)
							(end -0.3048 0.2032)
						)
						(arc
							(start -0.3048 -0.2032)
							(mid -0.275042 -0.275042)
							(end -0.2032 -0.3048)
						)
						(arc
							(start 0.2032 -0.3048)
							(mid 0.275042 -0.275042)
							(end 0.3048 -0.2032)
						)
					)
					(width 0)
					(fill yes)
				)
			)
		)
		(pad "2" smd custom
			(at 0 0.4445 90)
			(size 0.1524 0.1524)
			(layers "B.Cu" "B.Mask" "B.Paste")
			(net "GND")
			(options
				(clearance outline)
				(anchor circle)
			)
			(primitives
				(gr_poly
					(pts
						(arc
							(start 0.3048 0.2032)
							(mid 0.275042 0.275042)
							(end 0.2032 0.3048)
						)
						(arc
							(start -0.2032 0.3048)
							(mid -0.275042 0.275042)
							(end -0.3048 0.2032)
						)
						(arc
							(start -0.3048 -0.2032)
							(mid -0.275042 -0.275042)
							(end -0.2032 -0.3048)
						)
						(arc
							(start 0.2032 -0.3048)
							(mid 0.275042 -0.275042)
							(end 0.3048 -0.2032)
						)
					)
					(width 0)
					(fill yes)
				)
			)
		)
	)
	(footprint ""
		(layer "B.Cu")
		(at 15.833344 -175.260762 90)
		(property "Reference" "SC1116"
			(at 0 0 90)
			(layer "B.SilkS")
			(hide yes)
			(effects
				(font
					(size 1.27 1.27)
				)
				(justify mirror)
			)
		)
		(property "Value" "SCD1U16V2KX-3GP"
			(at -1.1811 -2.7051 90)
			(unlocked yes)
			(layer "B.Fab")
			(hide yes)
			(effects
				(font
					(size 1.016 1.016)
					(thickness 0.1524)
				)
				(justify mirror)
			)
		)
		(property "Device Type" "C402H22"
			(at -1.1811 -4.2291 90)
			(unlocked yes)
			(layer "B.Fab")
			(hide yes)
			(effects
				(font
					(size 1.016 1.016)
					(thickness 0.1524)
				)
				(justify mirror)
			)
		)
		(duplicate_pad_numbers_are_jumpers no)
		(fp_rect
			(start 0.4318 0.9525)
			(end -0.4318 -0.9525)
			(stroke
				(width 0)
				(type default)
			)
			(fill no)
			(layer "B.CrtYd")
		)
		(fp_rect
			(start 0.4318 0.9525)
			(end -0.4318 -0.9525)
			(stroke
				(width 0)
				(type default)
			)
			(fill no)
			(layer "B.Fab")
		)
		(pad "1" smd custom
			(at 0 -0.4445 270)
			(size 0.1524 0.1524)
			(layers "B.Cu" "B.Mask" "B.Paste")
			(net "P3V3_STBY")
			(options
				(clearance outline)
				(anchor circle)
			)
			(primitives
				(gr_poly
					(pts
						(arc
							(start 0.3048 0.2032)
							(mid 0.275042 0.275042)
							(end 0.2032 0.3048)
						)
						(arc
							(start -0.2032 0.3048)
							(mid -0.275042 0.275042)
							(end -0.3048 0.2032)
						)
						(arc
							(start -0.3048 -0.2032)
							(mid -0.275042 -0.275042)
							(end -0.2032 -0.3048)
						)
						(arc
							(start 0.2032 -0.3048)
							(mid 0.275042 -0.275042)
							(end 0.3048 -0.2032)
						)
					)
					(width 0)
					(fill yes)
				)
			)
		)
		(pad "2" smd custom
			(at 0 0.4445 270)
			(size 0.1524 0.1524)
			(layers "B.Cu" "B.Mask" "B.Paste")
			(net "GND")
			(options
				(clearance outline)
				(anchor circle)
			)
			(primitives
				(gr_poly
					(pts
						(arc
							(start 0.3048 0.2032)
							(mid 0.275042 0.275042)
							(end 0.2032 0.3048)
						)
						(arc
							(start -0.2032 0.3048)
							(mid -0.275042 0.275042)
							(end -0.3048 0.2032)
						)
						(arc
							(start -0.3048 -0.2032)
							(mid -0.275042 -0.275042)
							(end -0.2032 -0.3048)
						)
						(arc
							(start 0.2032 -0.3048)
							(mid 0.275042 -0.275042)
							(end 0.3048 -0.2032)
						)
					)
					(width 0)
					(fill yes)
				)
			)
		)
	)
	(footprint ""
		(layer "B.Cu")
		(at 119.90197 -84.836)
		(property "Reference" "STP114"
			(at 0 0 0)
			(layer "B.SilkS")
			(hide yes)
			(effects
				(font
					(size 1.27 1.27)
				)
				(justify mirror)
			)
		)
		(property "Value" "TPAD28"
			(at -0.0127 -1.8034 0)
			(unlocked yes)
			(layer "B.Fab")
			(hide yes)
			(effects
				(font
					(size 1.016 1.016)
					(thickness 0.1524)
				)
				(justify mirror)
			)
		)
		(property "Device Type" "TPAD28"
			(at -0.0127 -3.3274 0)
			(unlocked yes)
			(layer "B.Fab")
			(hide yes)
			(effects
				(font
					(size 1.016 1.016)
					(thickness 0.1524)
				)
				(justify mirror)
			)
		)
		(duplicate_pad_numbers_are_jumpers no)
		(fp_poly
			(pts
				(arc
					(start 0.3556 0)
					(mid -0.3556 0)
					(end 0.3556 0)
				)
			)
			(stroke
				(width 0)
				(type default)
			)
			(fill no)
			(layer "B.CrtYd")
		)
		(fp_poly
			(pts
				(arc
					(start 0.6096 0)
					(mid -0.6096 0)
					(end 0.6096 0)
				)
			)
			(stroke
				(width 0)
				(type default)
			)
			(fill no)
			(layer "B.Fab")
		)
		(pad "1" smd circle
			(at 0 0 180)
			(size 0.7112 0.7112)
			(layers "B.Cu" "B.Mask" "B.Paste")
			(net "TEST_MUX_47")
		)
	)
	(footprint ""
		(layer "B.Cu")
		(at 105.010966 -60.579 180)
		(property "Reference" "SR924"
			(at 0 0 0)
			(layer "B.SilkS")
			(hide yes)
			(effects
				(font
					(size 1.27 1.27)
				)
				(justify mirror)
			)
		)
		(property "Value" "0R2J-2-GP"
			(at -0.064008 -3.993896 180)
			(unlocked yes)
			(layer "B.Fab")
			(hide yes)
			(effects
				(font
					(size 1.016 1.016)
					(thickness 0.1524)
				)
				(justify mirror)
			)
		)
		(property "Device Type" "R402H16"
			(at -0.064008 -5.517896 180)
			(unlocked yes)
			(layer "B.Fab")
			(hide yes)
			(effects
				(font
					(size 1.016 1.016)
					(thickness 0.1524)
				)
				(justify mirror)
			)
		)
		(duplicate_pad_numbers_are_jumpers no)
		(fp_line
			(start 0.508 -0.9398)
			(end 0.508 0.9398)
			(stroke
				(width 0.1524)
				(type default)
			)
			(layer "B.SilkS")
		)
		(fp_line
			(start -0.508 -0.9398)
			(end 0.508 -0.9398)
			(stroke
				(width 0.1524)
				(type default)
			)
			(layer "B.SilkS")
		)
		(fp_rect
			(start 0.508 0.9398)
			(end -0.508 -0.9398)
			(stroke
				(width 0)
				(type default)
			)
			(fill no)
			(layer "B.CrtYd")
		)
		(fp_rect
			(start 0.508 0.9398)
			(end -0.508 -0.9398)
			(stroke
				(width 0)
				(type default)
			)
			(fill no)
			(layer "B.Fab")
		)
		(pad "1" smd custom
			(at 0 -0.4445)
			(size 0.1397 0.1397)
			(layers "B.Cu" "B.Mask" "B.Paste")
			(net "IOC_TDO")
			(options
				(clearance outline)
				(anchor circle)
			)
			(primitives
				(gr_poly
					(pts
						(arc
							(start -0.1778 0.2794)
							(mid -0.249642 0.249642)
							(end -0.2794 0.1778)
						)
						(arc
							(start -0.2794 -0.1778)
							(mid -0.249642 -0.249642)
							(end -0.1778 -0.2794)
						)
						(arc
							(start 0.1778 -0.2794)
							(mid 0.249642 -0.249642)
							(end 0.2794 -0.1778)
						)
						(arc
							(start 0.2794 0.1778)
							(mid 0.249642 0.249642)
							(end 0.1778 0.2794)
						)
					)
					(width 0)
					(fill yes)
				)
			)
		)
		(pad "2" smd custom
			(at 0 0.4445)
			(size 0.1397 0.1397)
			(layers "B.Cu" "B.Mask" "B.Paste")
			(net "JTAG_IOC_TDO")
			(options
				(clearance outline)
				(anchor circle)
			)
			(primitives
				(gr_poly
					(pts
						(arc
							(start -0.1778 0.2794)
							(mid -0.249642 0.249642)
							(end -0.2794 0.1778)
						)
						(arc
							(start -0.2794 -0.1778)
							(mid -0.249642 -0.249642)
							(end -0.1778 -0.2794)
						)
						(arc
							(start 0.1778 -0.2794)
							(mid 0.249642 -0.249642)
							(end 0.2794 -0.1778)
						)
						(arc
							(start 0.2794 0.1778)
							(mid 0.249642 0.249642)
							(end 0.1778 0.2794)
						)
					)
					(width 0)
					(fill yes)
				)
			)
		)
	)
	(footprint ""
		(layer "B.Cu")
		(at 274.193 -179.705 90)
		(property "Reference" "R353"
			(at 0 0 90)
			(layer "B.SilkS")
			(hide yes)
			(effects
				(font
					(size 1.27 1.27)
				)
				(justify mirror)
			)
		)
		(property "Value" "3K3R2F-2-GP"
			(at -0.064008 -3.993896 90)
			(unlocked yes)
			(layer "B.Fab")
			(hide yes)
			(effects
				(font
					(size 1.016 1.016)
					(thickness 0.1524)
				)
				(justify mirror)
			)
		)
		(property "Device Type" "R402H16"
			(at -0.064008 -5.517896 90)
			(unlocked yes)
			(layer "B.Fab")
			(hide yes)
			(effects
				(font
					(size 1.016 1.016)
					(thickness 0.1524)
				)
				(justify mirror)
			)
		)
		(duplicate_pad_numbers_are_jumpers no)
		(fp_line
			(start 0.508 -0.9398)
			(end 0.508 0.9398)
			(stroke
				(width 0.1524)
				(type default)
			)
			(layer "B.SilkS")
		)
		(fp_line
			(start -0.508 -0.9398)
			(end 0.508 -0.9398)
			(stroke
				(width 0.1524)
				(type default)
			)
			(layer "B.SilkS")
		)
		(fp_rect
			(start 0.508 0.9398)
			(end -0.508 -0.9398)
			(stroke
				(width 0)
				(type default)
			)
			(fill no)
			(layer "B.CrtYd")
		)
		(fp_rect
			(start 0.508 0.9398)
			(end -0.508 -0.9398)
			(stroke
				(width 0)
				(type default)
			)
			(fill no)
			(layer "B.Fab")
		)
		(pad "1" smd custom
			(at 0 -0.4445 270)
			(size 0.1397 0.1397)
			(layers "B.Cu" "B.Mask" "B.Paste")
			(net "P3V3_STBY")
			(options
				(clearance outline)
				(anchor circle)
			)
			(primitives
				(gr_poly
					(pts
						(arc
							(start -0.1778 0.2794)
							(mid -0.249642 0.249642)
							(end -0.2794 0.1778)
						)
						(arc
							(start -0.2794 -0.1778)
							(mid -0.249642 -0.249642)
							(end -0.1778 -0.2794)
						)
						(arc
							(start 0.1778 -0.2794)
							(mid 0.249642 -0.249642)
							(end 0.2794 -0.1778)
						)
						(arc
							(start 0.2794 0.1778)
							(mid 0.249642 0.249642)
							(end 0.1778 0.2794)
						)
					)
					(width 0)
					(fill yes)
				)
			)
		)
		(pad "2" smd custom
			(at 0 0.4445 270)
			(size 0.1397 0.1397)
			(layers "B.Cu" "B.Mask" "B.Paste")
			(net "ROMA19")
			(options
				(clearance outline)
				(anchor circle)
			)
			(primitives
				(gr_poly
					(pts
						(arc
							(start -0.1778 0.2794)
							(mid -0.249642 0.249642)
							(end -0.2794 0.1778)
						)
						(arc
							(start -0.2794 -0.1778)
							(mid -0.249642 -0.249642)
							(end -0.1778 -0.2794)
						)
						(arc
							(start 0.1778 -0.2794)
							(mid 0.249642 -0.249642)
							(end 0.2794 -0.1778)
						)
						(arc
							(start 0.2794 0.1778)
							(mid 0.249642 0.249642)
							(end 0.1778 0.2794)
						)
					)
					(width 0)
					(fill yes)
				)
			)
		)
	)
	(footprint ""
		(layer "B.Cu")
		(at 90.02014 -44.82084)
		(property "Reference" "STP49"
			(at 0 0 0)
			(layer "B.SilkS")
			(hide yes)
			(effects
				(font
					(size 1.27 1.27)
				)
				(justify mirror)
			)
		)
		(property "Value" "TPAD28"
			(at -0.0127 -1.8034 0)
			(unlocked yes)
			(layer "B.Fab")
			(hide yes)
			(effects
				(font
					(size 1.016 1.016)
					(thickness 0.1524)
				)
				(justify mirror)
			)
		)
		(property "Device Type" "TPAD28"
			(at -0.0127 -3.3274 0)
			(unlocked yes)
			(layer "B.Fab")
			(hide yes)
			(effects
				(font
					(size 1.016 1.016)
					(thickness 0.1524)
				)
				(justify mirror)
			)
		)
		(duplicate_pad_numbers_are_jumpers no)
		(fp_poly
			(pts
				(arc
					(start 0.3556 0)
					(mid -0.3556 0)
					(end 0.3556 0)
				)
			)
			(stroke
				(width 0)
				(type default)
			)
			(fill no)
			(layer "B.CrtYd")
		)
		(fp_poly
			(pts
				(arc
					(start 0.6096 0)
					(mid -0.6096 0)
					(end 0.6096 0)
				)
			)
			(stroke
				(width 0)
				(type default)
			)
			(fill no)
			(layer "B.Fab")
		)
		(pad "1" smd circle
			(at 0 0 180)
			(size 0.7112 0.7112)
			(layers "B.Cu" "B.Mask" "B.Paste")
			(net "OSC_REF_CLK")
		)
	)
	(footprint ""
		(layer "B.Cu")
		(at 291.914072 -172.131736 180)
		(property "Reference" "C218"
			(at 0 0 0)
			(layer "B.SilkS")
			(hide yes)
			(effects
				(font
					(size 1.27 1.27)
				)
				(justify mirror)
			)
		)
		(property "Value" "SC1U10V2KX-1GP"
			(at -1.1811 -2.7051 180)
			(unlocked yes)
			(layer "B.Fab")
			(hide yes)
			(effects
				(font
					(size 1.016 1.016)
					(thickness 0.1524)
				)
				(justify mirror)
			)
		)
		(property "Device Type" "C402H22"
			(at -1.1811 -4.2291 180)
			(unlocked yes)
			(layer "B.Fab")
			(hide yes)
			(effects
				(font
					(size 1.016 1.016)
					(thickness 0.1524)
				)
				(justify mirror)
			)
		)
		(duplicate_pad_numbers_are_jumpers no)
		(fp_rect
			(start 0.4318 0.9525)
			(end -0.4318 -0.9525)
			(stroke
				(width 0)
				(type default)
			)
			(fill no)
			(layer "B.CrtYd")
		)
		(fp_rect
			(start 0.4318 0.9525)
			(end -0.4318 -0.9525)
			(stroke
				(width 0)
				(type default)
			)
			(fill no)
			(layer "B.Fab")
		)
		(pad "1" smd custom
			(at 0 -0.4445)
			(size 0.1524 0.1524)
			(layers "B.Cu" "B.Mask" "B.Paste")
			(net "P3V3_STBY")
			(options
				(clearance outline)
				(anchor circle)
			)
			(primitives
				(gr_poly
					(pts
						(arc
							(start 0.3048 0.2032)
							(mid 0.275042 0.275042)
							(end 0.2032 0.3048)
						)
						(arc
							(start -0.2032 0.3048)
							(mid -0.275042 0.275042)
							(end -0.3048 0.2032)
						)
						(arc
							(start -0.3048 -0.2032)
							(mid -0.275042 -0.275042)
							(end -0.2032 -0.3048)
						)
						(arc
							(start 0.2032 -0.3048)
							(mid 0.275042 -0.275042)
							(end 0.3048 -0.2032)
						)
					)
					(width 0)
					(fill yes)
				)
			)
		)
		(pad "2" smd custom
			(at 0 0.4445)
			(size 0.1524 0.1524)
			(layers "B.Cu" "B.Mask" "B.Paste")
			(net "GND")
			(options
				(clearance outline)
				(anchor circle)
			)
			(primitives
				(gr_poly
					(pts
						(arc
							(start 0.3048 0.2032)
							(mid 0.275042 0.275042)
							(end 0.2032 0.3048)
						)
						(arc
							(start -0.2032 0.3048)
							(mid -0.275042 0.275042)
							(end -0.3048 0.2032)
						)
						(arc
							(start -0.3048 -0.2032)
							(mid -0.275042 -0.275042)
							(end -0.2032 -0.3048)
						)
						(arc
							(start 0.2032 -0.3048)
							(mid 0.275042 -0.275042)
							(end 0.3048 -0.2032)
						)
					)
					(width 0)
					(fill yes)
				)
			)
		)
	)
	(footprint ""
		(layer "B.Cu")
		(at 257.048 -13.97)
		(property "Reference" "U194"
			(at 0 0 0)
			(layer "B.SilkS")
			(hide yes)
			(effects
				(font
					(size 1.27 1.27)
				)
				(justify mirror)
			)
		)
		(property "Value" "TPS2065DBVT-GP"
			(at 0 -5.1308 0)
			(unlocked yes)
			(layer "B.Fab")
			(hide yes)
			(effects
				(font
					(size 1.016 1.016)
					(thickness 0.1524)
				)
				(justify mirror)
			)
		)
		(property "Device Type" "SOT-23-5H58"
			(at 0 -6.7564 0)
			(unlocked yes)
			(layer "B.Fab")
			(hide yes)
			(effects
				(font
					(size 1.016 1.016)
					(thickness 0.1524)
				)
				(justify mirror)
			)
		)
		(duplicate_pad_numbers_are_jumpers no)
		(fp_line
			(start -1.778 -2.286)
			(end 1.778 -2.286)
			(stroke
				(width 0.1524)
				(type default)
			)
			(layer "B.SilkS")
		)
		(fp_line
			(start -1.778 2.286)
			(end -1.778 -2.286)
			(stroke
				(width 0.1524)
				(type default)
			)
			(layer "B.SilkS")
		)
		(fp_line
			(start 0.254 2.286)
			(end -1.778 2.286)
			(stroke
				(width 0.1524)
				(type default)
			)
			(layer "B.SilkS")
		)
		(fp_line
			(start 0.7112 2.2352)
			(end 1.7272 2.2352)
			(stroke
				(width 0.3302)
				(type default)
			)
			(layer "B.SilkS")
		)
		(fp_line
			(start 1.7272 2.2352)
			(end 1.7272 0.762)
			(stroke
				(width 0.3302)
				(type default)
			)
			(layer "B.SilkS")
		)
		(fp_line
			(start 1.778 -2.286)
			(end 1.778 2.286)
			(stroke
				(width 0.1524)
				(type default)
			)
			(layer "B.SilkS")
		)
		(fp_line
			(start 1.778 2.286)
			(end -1.778 2.286)
			(stroke
				(width 0.1524)
				(type default)
			)
			(layer "B.SilkS")
		)
		(fp_line
			(start 1.778 2.286)
			(end 0.254 2.286)
			(stroke
				(width 0.1524)
				(type default)
			)
			(layer "B.SilkS")
		)
		(fp_poly
			(pts
				(xy 0.9652 2.4384) (xy 1.3208 2.794) (xy 0.6096 2.794)
			)
			(stroke
				(width 0)
				(type default)
			)
			(fill yes)
			(layer "B.SilkS")
		)
		(fp_rect
			(start 1.778 2.286)
			(end -1.778 -2.286)
			(stroke
				(width 0)
				(type default)
			)
			(fill no)
			(layer "B.CrtYd")
		)
		(fp_rect
			(start 1.778 2.286)
			(end -1.778 -2.286)
			(stroke
				(width 0)
				(type default)
			)
			(fill no)
			(layer "B.Fab")
		)
		(pad "1" smd rect
			(at 0.94996 1.143 180)
			(size 0.508 1.524)
			(layers "B.Cu" "B.Mask" "B.Paste")
			(net "P5V_USB")
		)
		(pad "2" smd rect
			(at 0 1.143 180)
			(size 0.508 1.524)
			(layers "B.Cu" "B.Mask" "B.Paste")
			(net "GND")
		)
		(pad "3" smd rect
			(at -0.94996 1.143 180)
			(size 0.508 1.524)
			(layers "B.Cu" "B.Mask" "B.Paste")
			(net "USB_OCS_N1")
		)
		(pad "4" smd rect
			(at -0.94996 -1.143 180)
			(size 0.508 1.524)
			(layers "B.Cu" "B.Mask" "B.Paste")
			(net "USB_EN_1")
		)
		(pad "5" smd rect
			(at 0.94996 -1.143 180)
			(size 0.508 1.524)
			(layers "B.Cu" "B.Mask" "B.Paste")
			(net "P5V_USB_BP1_F")
		)
	)
	(footprint ""
		(layer "B.Cu")
		(at 113.93297 -85.852 90)
		(property "Reference" "STP57"
			(at 0 0 90)
			(layer "B.SilkS")
			(hide yes)
			(effects
				(font
					(size 1.27 1.27)
				)
				(justify mirror)
			)
		)
		(property "Value" "TPAD28"
			(at -0.0127 -1.8034 90)
			(unlocked yes)
			(layer "B.Fab")
			(hide yes)
			(effects
				(font
					(size 1.016 1.016)
					(thickness 0.1524)
				)
				(justify mirror)
			)
		)
		(property "Device Type" "TPAD28"
			(at -0.0127 -3.3274 90)
			(unlocked yes)
			(layer "B.Fab")
			(hide yes)
			(effects
				(font
					(size 1.016 1.016)
					(thickness 0.1524)
				)
				(justify mirror)
			)
		)
		(duplicate_pad_numbers_are_jumpers no)
		(fp_poly
			(pts
				(arc
					(start 0 0.3556)
					(mid 0 -0.3556)
					(end 0 0.3556)
				)
			)
			(stroke
				(width 0)
				(type default)
			)
			(fill no)
			(layer "B.CrtYd")
		)
		(fp_poly
			(pts
				(arc
					(start 0 0.6096)
					(mid 0 -0.6096)
					(end 0 0.6096)
				)
			)
			(stroke
				(width 0)
				(type default)
			)
			(fill no)
			(layer "B.Fab")
		)
		(pad "1" smd circle
			(at 0 0 270)
			(size 0.7112 0.7112)
			(layers "B.Cu" "B.Mask" "B.Paste")
			(net "EXP_LED19")
		)
	)
)
